(kicad_pcb
	(version 20260206)
	(generator "pcbnew")
	(generator_version "10.0")
	(general
		(thickness 1.6)
		(legacy_teardrops no)
	)
	(paper "A4")
	(title_block
		(title "01162023_DA0F0TEBIF0_F0T_Expander_BD_F_brd_V02_OCP.brd")
		(comment 1 "Grand Teton / footprints 6323-6329 of 9728")
	)
	(layers
		(0 "F.Cu" signal "TOP")
		(4 "In1.Cu" signal "GND")
		(6 "In2.Cu" signal "VCC")
		(8 "In3.Cu" signal "VCC1")
		(10 "In4.Cu" signal "GND1")
		(12 "In5.Cu" signal "IN1")
		(14 "In6.Cu" signal "GND2")
		(16 "In7.Cu" signal "IN2")
		(18 "In8.Cu" signal "GND3")
		(20 "In9.Cu" signal "IN3")
		(22 "In10.Cu" signal "GND4")
		(24 "In11.Cu" signal "IN4")
		(26 "In12.Cu" signal "GND5")
		(28 "In13.Cu" signal "IN5")
		(30 "In14.Cu" signal "GND6")
		(32 "In15.Cu" signal "IN6")
		(34 "In16.Cu" signal "GND7")
		(2 "B.Cu" signal "BOTTOM")
		(9 "F.Adhes" user "F.Adhesive")
		(11 "B.Adhes" user "B.Adhesive")
		(13 "F.Paste" user "Package Geometry/Pastemask Top")
		(15 "B.Paste" user "Package Geometry/Pastemask Bottom")
		(5 "F.SilkS" user "Ref Des/Silkscreen Top")
		(7 "B.SilkS" user "Ref Des/Silkscreen Bottom")
		(1 "F.Mask" user "Board Geometry/Soldermask Top")
		(3 "B.Mask" user "Board Geometry/Soldermask Bottom")
		(17 "Dwgs.User" user "User.Drawings")
		(19 "Cmts.User" user "User.Comments")
		(21 "Eco1.User" user "User.Eco1")
		(23 "Eco2.User" user "User.Eco2")
		(25 "Edge.Cuts" user "Board Geometry/Outline")
		(27 "Margin" user)
		(31 "F.CrtYd" user "Package Geometry/Place Bound Top")
		(29 "B.CrtYd" user "Package Geometry/Place Bound Bottom")
		(35 "F.Fab" user "Ref Des/Assembly Top")
		(33 "B.Fab" user "Ref Des/Assembly Bottom")
	)
	(footprint ""
		(layer "F.Cu")
		(at 31.29407 -35.264852)
		(property "Reference" "R5651"
			(at 0 0 0)
			(layer "F.SilkS")
			(hide yes)
			(effects
				(font
					(size 1.27 1.27)
				)
			)
		)
		(property "Value" ""
			(at 0 0 0)
			(layer "F.Fab")
			(effects
				(font
					(size 1.27 1.27)
				)
			)
		)
		(duplicate_pad_numbers_are_jumpers no)
		(fp_line
			(start -0.7874 -0.4064)
			(end 0.7874 -0.4064)
			(stroke
				(width 0.1524)
				(type default)
			)
			(layer "F.SilkS")
		)
		(fp_line
			(start -0.7874 0.4064)
			(end -0.7874 -0.4064)
			(stroke
				(width 0.1524)
				(type default)
			)
			(layer "F.SilkS")
		)
		(fp_line
			(start 0.7874 -0.4064)
			(end 0.7874 0.4064)
			(stroke
				(width 0.1524)
				(type default)
			)
			(layer "F.SilkS")
		)
		(fp_line
			(start 0.7874 0.4064)
			(end -0.7874 0.4064)
			(stroke
				(width 0.1524)
				(type default)
			)
			(layer "F.SilkS")
		)
		(fp_line
			(start -0.67945 -0.305054)
			(end -0.12065 -0.305054)
			(stroke
				(width 0.1)
				(type default)
			)
			(layer "F.Fab")
		)
		(fp_line
			(start -0.67945 0.3048)
			(end -0.67945 -0.305054)
			(stroke
				(width 0.1)
				(type default)
			)
			(layer "F.Fab")
		)
		(fp_line
			(start -0.12065 -0.305054)
			(end -0.12065 -0.2794)
			(stroke
				(width 0.1)
				(type default)
			)
			(layer "F.Fab")
		)
		(fp_line
			(start -0.12065 -0.2794)
			(end 0.12065 -0.2794)
			(stroke
				(width 0.1)
				(type default)
			)
			(layer "F.Fab")
		)
		(fp_line
			(start -0.12065 0.2794)
			(end -0.12065 0.3048)
			(stroke
				(width 0.1)
				(type default)
			)
			(layer "F.Fab")
		)
		(fp_line
			(start -0.12065 0.3048)
			(end -0.67945 0.3048)
			(stroke
				(width 0.1)
				(type default)
			)
			(layer "F.Fab")
		)
		(fp_line
			(start 0.120396 0.2794)
			(end -0.12065 0.2794)
			(stroke
				(width 0.1)
				(type default)
			)
			(layer "F.Fab")
		)
		(fp_line
			(start 0.120396 0.3048)
			(end 0.120396 0.2794)
			(stroke
				(width 0.1)
				(type default)
			)
			(layer "F.Fab")
		)
		(fp_line
			(start 0.12065 -0.3048)
			(end 0.67945 -0.3048)
			(stroke
				(width 0.1)
				(type default)
			)
			(layer "F.Fab")
		)
		(fp_line
			(start 0.12065 -0.2794)
			(end 0.12065 -0.3048)
			(stroke
				(width 0.1)
				(type default)
			)
			(layer "F.Fab")
		)
		(fp_line
			(start 0.67945 -0.3048)
			(end 0.67945 0.3048)
			(stroke
				(width 0.1)
				(type default)
			)
			(layer "F.Fab")
		)
		(fp_line
			(start 0.67945 0.3048)
			(end 0.120396 0.3048)
			(stroke
				(width 0.1)
				(type default)
			)
			(layer "F.Fab")
		)
		(pad "1" smd circle
			(at -0.40005 0)
			(size 0 0)
			(layers "F.Cu" "F.Mask" "F.Paste")
			(net "RST_SMB_SSD1_ISO_N")
		)
		(pad "2" smd circle
			(at 0.40005 0)
			(size 0 0)
			(layers "F.Cu" "F.Mask" "F.Paste")
			(net "GND")
		)
	)
	(footprint ""
		(layer "F.Cu")
		(at 336.042 -172.085 180)
		(property "Reference" "R4764"
			(at 0 0 180)
			(layer "F.SilkS")
			(hide yes)
			(effects
				(font
					(size 1.27 1.27)
				)
			)
		)
		(property "Value" ""
			(at 0 0 180)
			(layer "F.Fab")
			(effects
				(font
					(size 1.27 1.27)
				)
			)
		)
		(duplicate_pad_numbers_are_jumpers no)
		(fp_line
			(start 0.7874 0.4064)
			(end -0.7874 0.4064)
			(stroke
				(width 0.1524)
				(type default)
			)
			(layer "F.SilkS")
		)
		(fp_line
			(start 0.7874 -0.4064)
			(end 0.7874 0.4064)
			(stroke
				(width 0.1524)
				(type default)
			)
			(layer "F.SilkS")
		)
		(fp_line
			(start -0.7874 0.4064)
			(end -0.7874 -0.4064)
			(stroke
				(width 0.1524)
				(type default)
			)
			(layer "F.SilkS")
		)
		(fp_line
			(start -0.7874 -0.4064)
			(end 0.7874 -0.4064)
			(stroke
				(width 0.1524)
				(type default)
			)
			(layer "F.SilkS")
		)
		(fp_line
			(start 0.67945 0.3048)
			(end 0.120396 0.3048)
			(stroke
				(width 0.1)
				(type default)
			)
			(layer "F.Fab")
		)
		(fp_line
			(start 0.67945 -0.3048)
			(end 0.67945 0.3048)
			(stroke
				(width 0.1)
				(type default)
			)
			(layer "F.Fab")
		)
		(fp_line
			(start 0.12065 -0.2794)
			(end 0.12065 -0.3048)
			(stroke
				(width 0.1)
				(type default)
			)
			(layer "F.Fab")
		)
		(fp_line
			(start 0.12065 -0.3048)
			(end 0.67945 -0.3048)
			(stroke
				(width 0.1)
				(type default)
			)
			(layer "F.Fab")
		)
		(fp_line
			(start 0.120396 0.3048)
			(end 0.120396 0.2794)
			(stroke
				(width 0.1)
				(type default)
			)
			(layer "F.Fab")
		)
		(fp_line
			(start 0.120396 0.2794)
			(end -0.12065 0.2794)
			(stroke
				(width 0.1)
				(type default)
			)
			(layer "F.Fab")
		)
		(fp_line
			(start -0.12065 0.3048)
			(end -0.67945 0.3048)
			(stroke
				(width 0.1)
				(type default)
			)
			(layer "F.Fab")
		)
		(fp_line
			(start -0.12065 0.2794)
			(end -0.12065 0.3048)
			(stroke
				(width 0.1)
				(type default)
			)
			(layer "F.Fab")
		)
		(fp_line
			(start -0.12065 -0.2794)
			(end 0.12065 -0.2794)
			(stroke
				(width 0.1)
				(type default)
			)
			(layer "F.Fab")
		)
		(fp_line
			(start -0.12065 -0.305054)
			(end -0.12065 -0.2794)
			(stroke
				(width 0.1)
				(type default)
			)
			(layer "F.Fab")
		)
		(fp_line
			(start -0.67945 0.3048)
			(end -0.67945 -0.305054)
			(stroke
				(width 0.1)
				(type default)
			)
			(layer "F.Fab")
		)
		(fp_line
			(start -0.67945 -0.305054)
			(end -0.12065 -0.305054)
			(stroke
				(width 0.1)
				(type default)
			)
			(layer "F.Fab")
		)
		(pad "1" smd circle
			(at -0.40005 0 180)
			(size 0 0)
			(layers "F.Cu" "F.Mask" "F.Paste")
			(net "PCA9555_1_PEX2_A2")
		)
		(pad "2" smd circle
			(at 0.40005 0 180)
			(size 0 0)
			(layers "F.Cu" "F.Mask" "F.Paste")
			(net "P3V3_AUX")
		)
	)
	(footprint ""
		(layer "F.Cu")
		(at 200.219056 -59.574684 90)
		(property "Reference" "PC528"
			(at 0 0 90)
			(layer "F.SilkS")
			(hide yes)
			(effects
				(font
					(size 1.27 1.27)
				)
			)
		)
		(property "Value" ""
			(at 0 0 90)
			(layer "F.Fab")
			(effects
				(font
					(size 1.27 1.27)
				)
			)
		)
		(duplicate_pad_numbers_are_jumpers no)
		(fp_line
			(start 0.7874 -0.4064)
			(end 0.7874 0.4064)
			(stroke
				(width 0.1524)
				(type default)
			)
			(layer "F.SilkS")
		)
		(fp_line
			(start -0.7874 -0.4064)
			(end 0.7874 -0.4064)
			(stroke
				(width 0.1524)
				(type default)
			)
			(layer "F.SilkS")
		)
		(fp_line
			(start 0.7874 0.4064)
			(end -0.7874 0.4064)
			(stroke
				(width 0.1524)
				(type default)
			)
			(layer "F.SilkS")
		)
		(fp_line
			(start -0.7874 0.4064)
			(end -0.7874 -0.4064)
			(stroke
				(width 0.1524)
				(type default)
			)
			(layer "F.SilkS")
		)
		(fp_line
			(start -0.12065 -0.305054)
			(end -0.12065 -0.2794)
			(stroke
				(width 0.1)
				(type default)
			)
			(layer "F.Fab")
		)
		(fp_line
			(start -0.67945 -0.305054)
			(end -0.12065 -0.305054)
			(stroke
				(width 0.1)
				(type default)
			)
			(layer "F.Fab")
		)
		(fp_line
			(start 0.67945 -0.3048)
			(end 0.67945 0.3048)
			(stroke
				(width 0.1)
				(type default)
			)
			(layer "F.Fab")
		)
		(fp_line
			(start 0.12065 -0.3048)
			(end 0.67945 -0.3048)
			(stroke
				(width 0.1)
				(type default)
			)
			(layer "F.Fab")
		)
		(fp_line
			(start 0.12065 -0.2794)
			(end 0.12065 -0.3048)
			(stroke
				(width 0.1)
				(type default)
			)
			(layer "F.Fab")
		)
		(fp_line
			(start -0.12065 -0.2794)
			(end 0.12065 -0.2794)
			(stroke
				(width 0.1)
				(type default)
			)
			(layer "F.Fab")
		)
		(fp_line
			(start 0.120396 0.2794)
			(end -0.12065 0.2794)
			(stroke
				(width 0.1)
				(type default)
			)
			(layer "F.Fab")
		)
		(fp_line
			(start -0.12065 0.2794)
			(end -0.12065 0.3048)
			(stroke
				(width 0.1)
				(type default)
			)
			(layer "F.Fab")
		)
		(fp_line
			(start 0.67945 0.3048)
			(end 0.120396 0.3048)
			(stroke
				(width 0.1)
				(type default)
			)
			(layer "F.Fab")
		)
		(fp_line
			(start 0.120396 0.3048)
			(end 0.120396 0.2794)
			(stroke
				(width 0.1)
				(type default)
			)
			(layer "F.Fab")
		)
		(fp_line
			(start -0.12065 0.3048)
			(end -0.67945 0.3048)
			(stroke
				(width 0.1)
				(type default)
			)
			(layer "F.Fab")
		)
		(fp_line
			(start -0.67945 0.3048)
			(end -0.67945 -0.305054)
			(stroke
				(width 0.1)
				(type default)
			)
			(layer "F.Fab")
		)
		(pad "1" smd circle
			(at -0.40005 0 90)
			(size 0 0)
			(layers "F.Cu" "F.Mask" "F.Paste")
			(net "P5V_AUX")
		)
		(pad "2" smd circle
			(at 0.40005 0 90)
			(size 0 0)
			(layers "F.Cu" "F.Mask" "F.Paste")
			(net "GND")
		)
	)
	(footprint ""
		(layer "F.Cu")
		(at 420.573962 -72.766682 90)
		(property "Reference" "PR7093"
			(at 0 0 90)
			(layer "F.SilkS")
			(hide yes)
			(effects
				(font
					(size 1.27 1.27)
				)
			)
		)
		(property "Value" ""
			(at 0 0 90)
			(layer "F.Fab")
			(effects
				(font
					(size 1.27 1.27)
				)
			)
		)
		(duplicate_pad_numbers_are_jumpers no)
		(fp_line
			(start 0.7874 -0.4064)
			(end 0.7874 0.4064)
			(stroke
				(width 0.1524)
				(type default)
			)
			(layer "F.SilkS")
		)
		(fp_line
			(start -0.7874 -0.4064)
			(end 0.7874 -0.4064)
			(stroke
				(width 0.1524)
				(type default)
			)
			(layer "F.SilkS")
		)
		(fp_line
			(start 0.7874 0.4064)
			(end -0.7874 0.4064)
			(stroke
				(width 0.1524)
				(type default)
			)
			(layer "F.SilkS")
		)
		(fp_line
			(start -0.7874 0.4064)
			(end -0.7874 -0.4064)
			(stroke
				(width 0.1524)
				(type default)
			)
			(layer "F.SilkS")
		)
		(fp_line
			(start -0.12065 -0.305054)
			(end -0.12065 -0.2794)
			(stroke
				(width 0.1)
				(type default)
			)
			(layer "F.Fab")
		)
		(fp_line
			(start -0.67945 -0.305054)
			(end -0.12065 -0.305054)
			(stroke
				(width 0.1)
				(type default)
			)
			(layer "F.Fab")
		)
		(fp_line
			(start 0.67945 -0.3048)
			(end 0.67945 0.3048)
			(stroke
				(width 0.1)
				(type default)
			)
			(layer "F.Fab")
		)
		(fp_line
			(start 0.12065 -0.3048)
			(end 0.67945 -0.3048)
			(stroke
				(width 0.1)
				(type default)
			)
			(layer "F.Fab")
		)
		(fp_line
			(start 0.12065 -0.2794)
			(end 0.12065 -0.3048)
			(stroke
				(width 0.1)
				(type default)
			)
			(layer "F.Fab")
		)
		(fp_line
			(start -0.12065 -0.2794)
			(end 0.12065 -0.2794)
			(stroke
				(width 0.1)
				(type default)
			)
			(layer "F.Fab")
		)
		(fp_line
			(start 0.120396 0.2794)
			(end -0.12065 0.2794)
			(stroke
				(width 0.1)
				(type default)
			)
			(layer "F.Fab")
		)
		(fp_line
			(start -0.12065 0.2794)
			(end -0.12065 0.3048)
			(stroke
				(width 0.1)
				(type default)
			)
			(layer "F.Fab")
		)
		(fp_line
			(start 0.67945 0.3048)
			(end 0.120396 0.3048)
			(stroke
				(width 0.1)
				(type default)
			)
			(layer "F.Fab")
		)
		(fp_line
			(start 0.120396 0.3048)
			(end 0.120396 0.2794)
			(stroke
				(width 0.1)
				(type default)
			)
			(layer "F.Fab")
		)
		(fp_line
			(start -0.12065 0.3048)
			(end -0.67945 0.3048)
			(stroke
				(width 0.1)
				(type default)
			)
			(layer "F.Fab")
		)
		(fp_line
			(start -0.67945 0.3048)
			(end -0.67945 -0.305054)
			(stroke
				(width 0.1)
				(type default)
			)
			(layer "F.Fab")
		)
		(pad "1" smd circle
			(at -0.40005 0 90)
			(size 0 0)
			(layers "F.Cu" "F.Mask" "F.Paste")
			(net "P12V_SSD14_CO_MODE")
		)
		(pad "2" smd circle
			(at 0.40005 0 90)
			(size 0 0)
			(layers "F.Cu" "F.Mask" "F.Paste")
			(net "GND")
		)
	)
	(footprint ""
		(layer "F.Cu")
		(at 295.852342 -350.098614 90)
		(property "Reference" "C2367"
			(at 0 0 90)
			(layer "F.SilkS")
			(hide yes)
			(effects
				(font
					(size 1.27 1.27)
				)
			)
		)
		(property "Value" ""
			(at 0 0 90)
			(layer "F.Fab")
			(effects
				(font
					(size 1.27 1.27)
				)
			)
		)
		(duplicate_pad_numbers_are_jumpers no)
		(fp_line
			(start 0.299974 -0.150114)
			(end 0.299974 0.150114)
			(stroke
				(width 0.1)
				(type default)
			)
			(layer "F.Fab")
		)
		(fp_line
			(start -0.299974 -0.150114)
			(end 0.299974 -0.150114)
			(stroke
				(width 0.1)
				(type default)
			)
			(layer "F.Fab")
		)
		(fp_line
			(start 0.299974 0.150114)
			(end -0.299974 0.150114)
			(stroke
				(width 0.1)
				(type default)
			)
			(layer "F.Fab")
		)
		(fp_line
			(start -0.299974 0.150114)
			(end -0.299974 -0.150114)
			(stroke
				(width 0.1)
				(type default)
			)
			(layer "F.Fab")
		)
		(pad "1" smd rect
			(at -0.2667 0 90)
			(size 0.3048 0.381)
			(layers "F.Cu" "F.Mask" "F.Paste")
			(net "P5E_PEX2_STN4_TX_DP<66>")
		)
		(pad "2" smd rect
			(at 0.2667 0 90)
			(size 0.3048 0.381)
			(layers "F.Cu" "F.Mask" "F.Paste")
			(net "P5E_PEX2_STN4_TX_C_DP<66>")
		)
	)
	(footprint ""
		(layer "F.Cu")
		(at 127.221996 -284.834838 90)
		(property "Reference" "PC109"
			(at 0 0 90)
			(layer "F.SilkS")
			(hide yes)
			(effects
				(font
					(size 1.27 1.27)
				)
			)
		)
		(property "Value" ""
			(at 0 0 90)
			(layer "F.Fab")
			(effects
				(font
					(size 1.27 1.27)
				)
			)
		)
		(duplicate_pad_numbers_are_jumpers no)
		(fp_line
			(start 0.7874 -0.4064)
			(end 0.7874 0.4064)
			(stroke
				(width 0.1524)
				(type default)
			)
			(layer "F.SilkS")
		)
		(fp_line
			(start -0.7874 -0.4064)
			(end 0.7874 -0.4064)
			(stroke
				(width 0.1524)
				(type default)
			)
			(layer "F.SilkS")
		)
		(fp_line
			(start 0.7874 0.4064)
			(end -0.7874 0.4064)
			(stroke
				(width 0.1524)
				(type default)
			)
			(layer "F.SilkS")
		)
		(fp_line
			(start -0.7874 0.4064)
			(end -0.7874 -0.4064)
			(stroke
				(width 0.1524)
				(type default)
			)
			(layer "F.SilkS")
		)
		(fp_line
			(start -0.12065 -0.305054)
			(end -0.12065 -0.2794)
			(stroke
				(width 0.1)
				(type default)
			)
			(layer "F.Fab")
		)
		(fp_line
			(start -0.67945 -0.305054)
			(end -0.12065 -0.305054)
			(stroke
				(width 0.1)
				(type default)
			)
			(layer "F.Fab")
		)
		(fp_line
			(start 0.67945 -0.3048)
			(end 0.67945 0.3048)
			(stroke
				(width 0.1)
				(type default)
			)
			(layer "F.Fab")
		)
		(fp_line
			(start 0.12065 -0.3048)
			(end 0.67945 -0.3048)
			(stroke
				(width 0.1)
				(type default)
			)
			(layer "F.Fab")
		)
		(fp_line
			(start 0.12065 -0.2794)
			(end 0.12065 -0.3048)
			(stroke
				(width 0.1)
				(type default)
			)
			(layer "F.Fab")
		)
		(fp_line
			(start -0.12065 -0.2794)
			(end 0.12065 -0.2794)
			(stroke
				(width 0.1)
				(type default)
			)
			(layer "F.Fab")
		)
		(fp_line
			(start 0.120396 0.2794)
			(end -0.12065 0.2794)
			(stroke
				(width 0.1)
				(type default)
			)
			(layer "F.Fab")
		)
		(fp_line
			(start -0.12065 0.2794)
			(end -0.12065 0.3048)
			(stroke
				(width 0.1)
				(type default)
			)
			(layer "F.Fab")
		)
		(fp_line
			(start 0.67945 0.3048)
			(end 0.120396 0.3048)
			(stroke
				(width 0.1)
				(type default)
			)
			(layer "F.Fab")
		)
		(fp_line
			(start 0.120396 0.3048)
			(end 0.120396 0.2794)
			(stroke
				(width 0.1)
				(type default)
			)
			(layer "F.Fab")
		)
		(fp_line
			(start -0.12065 0.3048)
			(end -0.67945 0.3048)
			(stroke
				(width 0.1)
				(type default)
			)
			(layer "F.Fab")
		)
		(fp_line
			(start -0.67945 0.3048)
			(end -0.67945 -0.305054)
			(stroke
				(width 0.1)
				(type default)
			)
			(layer "F.Fab")
		)
		(pad "1" smd circle
			(at -0.40005 0 90)
			(size 0 0)
			(layers "F.Cu" "F.Mask" "F.Paste")
			(net "SW_P12V_P0V8_PEX1_FLT")
		)
		(pad "2" smd circle
			(at 0.40005 0 90)
			(size 0 0)
			(layers "F.Cu" "F.Mask" "F.Paste")
			(net "GND")
		)
	)
	(footprint ""
		(layer "F.Cu")
		(at 206.623158 -88.993472)
		(property "Reference" "R5771"
			(at 0 0 0)
			(layer "F.SilkS")
			(hide yes)
			(effects
				(font
					(size 1.27 1.27)
				)
			)
		)
		(property "Value" ""
			(at 0 0 0)
			(layer "F.Fab")
			(effects
				(font
					(size 1.27 1.27)
				)
			)
		)
		(duplicate_pad_numbers_are_jumpers no)
		(fp_line
			(start -0.7874 -0.4064)
			(end 0.7874 -0.4064)
			(stroke
				(width 0.1524)
				(type default)
			)
			(layer "F.SilkS")
		)
		(fp_line
			(start -0.7874 0.4064)
			(end -0.7874 -0.4064)
			(stroke
				(width 0.1524)
				(type default)
			)
			(layer "F.SilkS")
		)
		(fp_line
			(start 0.7874 -0.4064)
			(end 0.7874 0.4064)
			(stroke
				(width 0.1524)
				(type default)
			)
			(layer "F.SilkS")
		)
		(fp_line
			(start 0.7874 0.4064)
			(end -0.7874 0.4064)
			(stroke
				(width 0.1524)
				(type default)
			)
			(layer "F.SilkS")
		)
		(fp_line
			(start -0.67945 -0.305054)
			(end -0.12065 -0.305054)
			(stroke
				(width 0.1)
				(type default)
			)
			(layer "F.Fab")
		)
		(fp_line
			(start -0.67945 0.3048)
			(end -0.67945 -0.305054)
			(stroke
				(width 0.1)
				(type default)
			)
			(layer "F.Fab")
		)
		(fp_line
			(start -0.12065 -0.305054)
			(end -0.12065 -0.2794)
			(stroke
				(width 0.1)
				(type default)
			)
			(layer "F.Fab")
		)
		(fp_line
			(start -0.12065 -0.2794)
			(end 0.12065 -0.2794)
			(stroke
				(width 0.1)
				(type default)
			)
			(layer "F.Fab")
		)
		(fp_line
			(start -0.12065 0.2794)
			(end -0.12065 0.3048)
			(stroke
				(width 0.1)
				(type default)
			)
			(layer "F.Fab")
		)
		(fp_line
			(start -0.12065 0.3048)
			(end -0.67945 0.3048)
			(stroke
				(width 0.1)
				(type default)
			)
			(layer "F.Fab")
		)
		(fp_line
			(start 0.120396 0.2794)
			(end -0.12065 0.2794)
			(stroke
				(width 0.1)
				(type default)
			)
			(layer "F.Fab")
		)
		(fp_line
			(start 0.120396 0.3048)
			(end 0.120396 0.2794)
			(stroke
				(width 0.1)
				(type default)
			)
			(layer "F.Fab")
		)
		(fp_line
			(start 0.12065 -0.3048)
			(end 0.67945 -0.3048)
			(stroke
				(width 0.1)
				(type default)
			)
			(layer "F.Fab")
		)
		(fp_line
			(start 0.12065 -0.2794)
			(end 0.12065 -0.3048)
			(stroke
				(width 0.1)
				(type default)
			)
			(layer "F.Fab")
		)
		(fp_line
			(start 0.67945 -0.3048)
			(end 0.67945 0.3048)
			(stroke
				(width 0.1)
				(type default)
			)
			(layer "F.Fab")
		)
		(fp_line
			(start 0.67945 0.3048)
			(end 0.120396 0.3048)
			(stroke
				(width 0.1)
				(type default)
			)
			(layer "F.Fab")
		)
		(pad "1" smd circle
			(at -0.40005 0)
			(size 0 0)
			(layers "F.Cu" "F.Mask" "F.Paste")
			(net "IRQ_SSD_LED_IOEXP_R_N")
		)
		(pad "2" smd circle
			(at 0.40005 0)
			(size 0 0)
			(layers "F.Cu" "F.Mask" "F.Paste")
			(net "IRQ_SSD_LED_IOEXP_N")
		)
	)
)
